(kicad_pcb
	(version 20260206)
	(generator "pcbnew")
	(generator_version "10.0")
	(general
		(thickness 1.6)
		(legacy_teardrops no)
	)
	(paper "A4")
	(title_block
		(title "03242023_DA0F0TMBIJ0_F0T_Motherboard_J_brd_V01_OCP.brd")
		(comment 1 "Grand Teton / footprints 2207-2213 of 6105")
	)
	(layers
		(0 "F.Cu" signal "TOP")
		(4 "In1.Cu" signal "GND")
		(6 "In2.Cu" signal "IN1")
		(8 "In3.Cu" signal "GND1")
		(10 "In4.Cu" signal "IN2")
		(12 "In5.Cu" signal "GND2")
		(14 "In6.Cu" signal "IN3")
		(16 "In7.Cu" signal "GND3")
		(18 "In8.Cu" signal "VCC")
		(20 "In9.Cu" signal "VCC1")
		(22 "In10.Cu" signal "GND4")
		(24 "In11.Cu" signal "IN4")
		(26 "In12.Cu" signal "GND5")
		(28 "In13.Cu" signal "IN5")
		(30 "In14.Cu" signal "GND6")
		(32 "In15.Cu" signal "IN6")
		(34 "In16.Cu" signal "GND7")
		(2 "B.Cu" signal "BOTTOM")
		(9 "F.Adhes" user "F.Adhesive")
		(11 "B.Adhes" user "B.Adhesive")
		(13 "F.Paste" user "Package Geometry/Pastemask Top")
		(15 "B.Paste" user "Package Geometry/Pastemask Bottom")
		(5 "F.SilkS" user "Ref Des/Silkscreen Top")
		(7 "B.SilkS" user "Ref Des/Silkscreen Bottom")
		(1 "F.Mask" user "Board Geometry/Soldermask Top")
		(3 "B.Mask" user "Board Geometry/Soldermask Bottom")
		(17 "Dwgs.User" user "User.Drawings")
		(19 "Cmts.User" user "User.Comments")
		(21 "Eco1.User" user "User.Eco1")
		(23 "Eco2.User" user "User.Eco2")
		(25 "Edge.Cuts" user "Board Geometry/Outline")
		(27 "Margin" user)
		(31 "F.CrtYd" user "Package Geometry/Place Bound Top")
		(29 "B.CrtYd" user "Package Geometry/Place Bound Bottom")
		(35 "F.Fab" user "Ref Des/Assembly Top")
		(33 "B.Fab" user "Ref Des/Assembly Bottom")
	)
	(footprint ""
		(layer "F.Cu")
		(at 365.46663 -255.053846 90)
		(property "Reference" "C1004"
			(at 0 0 90)
			(layer "F.SilkS")
			(hide yes)
			(effects
				(font
					(size 1.27 1.27)
				)
			)
		)
		(property "Value" ""
			(at 0 0 90)
			(layer "F.Fab")
			(effects
				(font
					(size 1.27 1.27)
				)
			)
		)
		(duplicate_pad_numbers_are_jumpers no)
		(fp_line
			(start 0.7874 -0.4064)
			(end 0.7874 0.4064)
			(stroke
				(width 0.1524)
				(type default)
			)
			(layer "F.SilkS")
		)
		(fp_line
			(start -0.7874 -0.4064)
			(end 0.7874 -0.4064)
			(stroke
				(width 0.1524)
				(type default)
			)
			(layer "F.SilkS")
		)
		(fp_line
			(start 0.7874 0.4064)
			(end -0.7874 0.4064)
			(stroke
				(width 0.1524)
				(type default)
			)
			(layer "F.SilkS")
		)
		(fp_line
			(start -0.7874 0.4064)
			(end -0.7874 -0.4064)
			(stroke
				(width 0.1524)
				(type default)
			)
			(layer "F.SilkS")
		)
		(fp_line
			(start -0.12065 -0.305054)
			(end -0.12065 -0.2794)
			(stroke
				(width 0.1)
				(type default)
			)
			(layer "F.Fab")
		)
		(fp_line
			(start -0.67945 -0.305054)
			(end -0.12065 -0.305054)
			(stroke
				(width 0.1)
				(type default)
			)
			(layer "F.Fab")
		)
		(fp_line
			(start 0.67945 -0.3048)
			(end 0.67945 0.3048)
			(stroke
				(width 0.1)
				(type default)
			)
			(layer "F.Fab")
		)
		(fp_line
			(start 0.12065 -0.3048)
			(end 0.67945 -0.3048)
			(stroke
				(width 0.1)
				(type default)
			)
			(layer "F.Fab")
		)
		(fp_line
			(start 0.12065 -0.2794)
			(end 0.12065 -0.3048)
			(stroke
				(width 0.1)
				(type default)
			)
			(layer "F.Fab")
		)
		(fp_line
			(start -0.12065 -0.2794)
			(end 0.12065 -0.2794)
			(stroke
				(width 0.1)
				(type default)
			)
			(layer "F.Fab")
		)
		(fp_line
			(start 0.120396 0.2794)
			(end -0.12065 0.2794)
			(stroke
				(width 0.1)
				(type default)
			)
			(layer "F.Fab")
		)
		(fp_line
			(start -0.12065 0.2794)
			(end -0.12065 0.3048)
			(stroke
				(width 0.1)
				(type default)
			)
			(layer "F.Fab")
		)
		(fp_line
			(start 0.67945 0.3048)
			(end 0.120396 0.3048)
			(stroke
				(width 0.1)
				(type default)
			)
			(layer "F.Fab")
		)
		(fp_line
			(start 0.120396 0.3048)
			(end 0.120396 0.2794)
			(stroke
				(width 0.1)
				(type default)
			)
			(layer "F.Fab")
		)
		(fp_line
			(start -0.12065 0.3048)
			(end -0.67945 0.3048)
			(stroke
				(width 0.1)
				(type default)
			)
			(layer "F.Fab")
		)
		(fp_line
			(start -0.67945 0.3048)
			(end -0.67945 -0.305054)
			(stroke
				(width 0.1)
				(type default)
			)
			(layer "F.Fab")
		)
		(pad "1" smd circle
			(at -0.40005 0 90)
			(size 0 0)
			(layers "F.Cu" "F.Mask" "F.Paste")
			(net "PVCCIN_CPU0")
		)
		(pad "2" smd circle
			(at 0.40005 0 90)
			(size 0 0)
			(layers "F.Cu" "F.Mask" "F.Paste")
			(net "GND")
		)
	)
	(footprint ""
		(layer "F.Cu")
		(at 452.486522 -75.093322)
		(property "Reference" "PR835"
			(at 0 0 0)
			(layer "F.SilkS")
			(hide yes)
			(effects
				(font
					(size 1.27 1.27)
				)
			)
		)
		(property "Value" ""
			(at 0 0 0)
			(layer "F.Fab")
			(effects
				(font
					(size 1.27 1.27)
				)
			)
		)
		(duplicate_pad_numbers_are_jumpers no)
		(fp_line
			(start -0.7874 -0.4064)
			(end 0.7874 -0.4064)
			(stroke
				(width 0.1524)
				(type default)
			)
			(layer "F.SilkS")
		)
		(fp_line
			(start -0.7874 0.4064)
			(end -0.7874 -0.4064)
			(stroke
				(width 0.1524)
				(type default)
			)
			(layer "F.SilkS")
		)
		(fp_line
			(start 0.7874 -0.4064)
			(end 0.7874 0.4064)
			(stroke
				(width 0.1524)
				(type default)
			)
			(layer "F.SilkS")
		)
		(fp_line
			(start 0.7874 0.4064)
			(end -0.7874 0.4064)
			(stroke
				(width 0.1524)
				(type default)
			)
			(layer "F.SilkS")
		)
		(fp_line
			(start -0.67945 -0.305054)
			(end -0.12065 -0.305054)
			(stroke
				(width 0.1)
				(type default)
			)
			(layer "F.Fab")
		)
		(fp_line
			(start -0.67945 0.3048)
			(end -0.67945 -0.305054)
			(stroke
				(width 0.1)
				(type default)
			)
			(layer "F.Fab")
		)
		(fp_line
			(start -0.12065 -0.305054)
			(end -0.12065 -0.2794)
			(stroke
				(width 0.1)
				(type default)
			)
			(layer "F.Fab")
		)
		(fp_line
			(start -0.12065 -0.2794)
			(end 0.12065 -0.2794)
			(stroke
				(width 0.1)
				(type default)
			)
			(layer "F.Fab")
		)
		(fp_line
			(start -0.12065 0.2794)
			(end -0.12065 0.3048)
			(stroke
				(width 0.1)
				(type default)
			)
			(layer "F.Fab")
		)
		(fp_line
			(start -0.12065 0.3048)
			(end -0.67945 0.3048)
			(stroke
				(width 0.1)
				(type default)
			)
			(layer "F.Fab")
		)
		(fp_line
			(start 0.120396 0.2794)
			(end -0.12065 0.2794)
			(stroke
				(width 0.1)
				(type default)
			)
			(layer "F.Fab")
		)
		(fp_line
			(start 0.120396 0.3048)
			(end 0.120396 0.2794)
			(stroke
				(width 0.1)
				(type default)
			)
			(layer "F.Fab")
		)
		(fp_line
			(start 0.12065 -0.3048)
			(end 0.67945 -0.3048)
			(stroke
				(width 0.1)
				(type default)
			)
			(layer "F.Fab")
		)
		(fp_line
			(start 0.12065 -0.2794)
			(end 0.12065 -0.3048)
			(stroke
				(width 0.1)
				(type default)
			)
			(layer "F.Fab")
		)
		(fp_line
			(start 0.67945 -0.3048)
			(end 0.67945 0.3048)
			(stroke
				(width 0.1)
				(type default)
			)
			(layer "F.Fab")
		)
		(fp_line
			(start 0.67945 0.3048)
			(end 0.120396 0.3048)
			(stroke
				(width 0.1)
				(type default)
			)
			(layer "F.Fab")
		)
		(pad "1" smd circle
			(at -0.40005 0)
			(size 0 0)
			(layers "F.Cu" "F.Mask" "F.Paste")
			(net "SW_P3V3_AUX_BOOT")
		)
		(pad "2" smd circle
			(at 0.40005 0)
			(size 0 0)
			(layers "F.Cu" "F.Mask" "F.Paste")
			(net "SW_P3V3_AUX_BOOT_R")
		)
	)
	(footprint ""
		(layer "F.Cu")
		(at 157.802834 -402.371052 -90)
		(property "Reference" "C766"
			(at 0 0 270)
			(layer "F.SilkS")
			(hide yes)
			(effects
				(font
					(size 1.27 1.27)
				)
			)
		)
		(property "Value" ""
			(at 0 0 270)
			(layer "F.Fab")
			(effects
				(font
					(size 1.27 1.27)
				)
			)
		)
		(duplicate_pad_numbers_are_jumpers no)
		(fp_line
			(start -0.299974 0.150114)
			(end -0.299974 -0.150114)
			(stroke
				(width 0.1)
				(type default)
			)
			(layer "F.Fab")
		)
		(fp_line
			(start 0.299974 0.150114)
			(end -0.299974 0.150114)
			(stroke
				(width 0.1)
				(type default)
			)
			(layer "F.Fab")
		)
		(fp_line
			(start -0.299974 -0.150114)
			(end 0.299974 -0.150114)
			(stroke
				(width 0.1)
				(type default)
			)
			(layer "F.Fab")
		)
		(fp_line
			(start 0.299974 -0.150114)
			(end 0.299974 0.150114)
			(stroke
				(width 0.1)
				(type default)
			)
			(layer "F.Fab")
		)
		(pad "1" smd rect
			(at -0.2667 0 270)
			(size 0.3048 0.381)
			(layers "F.Cu" "F.Mask" "F.Paste")
			(net "P5E_CPU1_PE2_TX_C_DN<3>")
		)
		(pad "2" smd rect
			(at 0.2667 0 270)
			(size 0.3048 0.381)
			(layers "F.Cu" "F.Mask" "F.Paste")
			(net "P5E_CPU1_PE2_TX_DN<3>")
		)
	)
	(footprint ""
		(layer "F.Cu")
		(at 235.413042 -245.402608 90)
		(property "Reference" "R4078"
			(at 0 0 90)
			(layer "F.SilkS")
			(hide yes)
			(effects
				(font
					(size 1.27 1.27)
				)
			)
		)
		(property "Value" ""
			(at 0 0 90)
			(layer "F.Fab")
			(effects
				(font
					(size 1.27 1.27)
				)
			)
		)
		(duplicate_pad_numbers_are_jumpers no)
		(fp_line
			(start 0.7874 -0.4064)
			(end 0.7874 0.4064)
			(stroke
				(width 0.1524)
				(type default)
			)
			(layer "F.SilkS")
		)
		(fp_line
			(start -0.7874 -0.4064)
			(end 0.7874 -0.4064)
			(stroke
				(width 0.1524)
				(type default)
			)
			(layer "F.SilkS")
		)
		(fp_line
			(start 0.7874 0.4064)
			(end -0.7874 0.4064)
			(stroke
				(width 0.1524)
				(type default)
			)
			(layer "F.SilkS")
		)
		(fp_line
			(start -0.7874 0.4064)
			(end -0.7874 -0.4064)
			(stroke
				(width 0.1524)
				(type default)
			)
			(layer "F.SilkS")
		)
		(fp_line
			(start -0.12065 -0.305054)
			(end -0.12065 -0.2794)
			(stroke
				(width 0.1)
				(type default)
			)
			(layer "F.Fab")
		)
		(fp_line
			(start -0.67945 -0.305054)
			(end -0.12065 -0.305054)
			(stroke
				(width 0.1)
				(type default)
			)
			(layer "F.Fab")
		)
		(fp_line
			(start 0.67945 -0.3048)
			(end 0.67945 0.3048)
			(stroke
				(width 0.1)
				(type default)
			)
			(layer "F.Fab")
		)
		(fp_line
			(start 0.12065 -0.3048)
			(end 0.67945 -0.3048)
			(stroke
				(width 0.1)
				(type default)
			)
			(layer "F.Fab")
		)
		(fp_line
			(start 0.12065 -0.2794)
			(end 0.12065 -0.3048)
			(stroke
				(width 0.1)
				(type default)
			)
			(layer "F.Fab")
		)
		(fp_line
			(start -0.12065 -0.2794)
			(end 0.12065 -0.2794)
			(stroke
				(width 0.1)
				(type default)
			)
			(layer "F.Fab")
		)
		(fp_line
			(start 0.120396 0.2794)
			(end -0.12065 0.2794)
			(stroke
				(width 0.1)
				(type default)
			)
			(layer "F.Fab")
		)
		(fp_line
			(start -0.12065 0.2794)
			(end -0.12065 0.3048)
			(stroke
				(width 0.1)
				(type default)
			)
			(layer "F.Fab")
		)
		(fp_line
			(start 0.67945 0.3048)
			(end 0.120396 0.3048)
			(stroke
				(width 0.1)
				(type default)
			)
			(layer "F.Fab")
		)
		(fp_line
			(start 0.120396 0.3048)
			(end 0.120396 0.2794)
			(stroke
				(width 0.1)
				(type default)
			)
			(layer "F.Fab")
		)
		(fp_line
			(start -0.12065 0.3048)
			(end -0.67945 0.3048)
			(stroke
				(width 0.1)
				(type default)
			)
			(layer "F.Fab")
		)
		(fp_line
			(start -0.67945 0.3048)
			(end -0.67945 -0.305054)
			(stroke
				(width 0.1)
				(type default)
			)
			(layer "F.Fab")
		)
		(pad "1" smd circle
			(at -0.40005 0 90)
			(size 0 0)
			(layers "F.Cu" "F.Mask" "F.Paste")
			(net "P3V3_AUX")
		)
		(pad "2" smd circle
			(at 0.40005 0 90)
			(size 0 0)
			(layers "F.Cu" "F.Mask" "F.Paste")
			(net "FG_SS_EN")
		)
	)
	(footprint ""
		(layer "F.Cu")
		(at 90.623136 -341.729822 -90)
		(property "Reference" "PC509"
			(at 0 0 270)
			(layer "F.SilkS")
			(hide yes)
			(effects
				(font
					(size 1.27 1.27)
				)
			)
		)
		(property "Value" ""
			(at 0 0 270)
			(layer "F.Fab")
			(effects
				(font
					(size 1.27 1.27)
				)
			)
		)
		(duplicate_pad_numbers_are_jumpers no)
		(fp_line
			(start -0.7874 0.4064)
			(end -0.7874 -0.4064)
			(stroke
				(width 0.1524)
				(type default)
			)
			(layer "F.SilkS")
		)
		(fp_line
			(start 0.7874 0.4064)
			(end -0.7874 0.4064)
			(stroke
				(width 0.1524)
				(type default)
			)
			(layer "F.SilkS")
		)
		(fp_line
			(start -0.7874 -0.4064)
			(end 0.7874 -0.4064)
			(stroke
				(width 0.1524)
				(type default)
			)
			(layer "F.SilkS")
		)
		(fp_line
			(start 0.7874 -0.4064)
			(end 0.7874 0.4064)
			(stroke
				(width 0.1524)
				(type default)
			)
			(layer "F.SilkS")
		)
		(fp_line
			(start -0.67945 0.3048)
			(end -0.67945 -0.305054)
			(stroke
				(width 0.1)
				(type default)
			)
			(layer "F.Fab")
		)
		(fp_line
			(start -0.12065 0.3048)
			(end -0.67945 0.3048)
			(stroke
				(width 0.1)
				(type default)
			)
			(layer "F.Fab")
		)
		(fp_line
			(start 0.120396 0.3048)
			(end 0.120396 0.2794)
			(stroke
				(width 0.1)
				(type default)
			)
			(layer "F.Fab")
		)
		(fp_line
			(start 0.67945 0.3048)
			(end 0.120396 0.3048)
			(stroke
				(width 0.1)
				(type default)
			)
			(layer "F.Fab")
		)
		(fp_line
			(start -0.12065 0.2794)
			(end -0.12065 0.3048)
			(stroke
				(width 0.1)
				(type default)
			)
			(layer "F.Fab")
		)
		(fp_line
			(start 0.120396 0.2794)
			(end -0.12065 0.2794)
			(stroke
				(width 0.1)
				(type default)
			)
			(layer "F.Fab")
		)
		(fp_line
			(start -0.12065 -0.2794)
			(end 0.12065 -0.2794)
			(stroke
				(width 0.1)
				(type default)
			)
			(layer "F.Fab")
		)
		(fp_line
			(start 0.12065 -0.2794)
			(end 0.12065 -0.3048)
			(stroke
				(width 0.1)
				(type default)
			)
			(layer "F.Fab")
		)
		(fp_line
			(start 0.12065 -0.3048)
			(end 0.67945 -0.3048)
			(stroke
				(width 0.1)
				(type default)
			)
			(layer "F.Fab")
		)
		(fp_line
			(start 0.67945 -0.3048)
			(end 0.67945 0.3048)
			(stroke
				(width 0.1)
				(type default)
			)
			(layer "F.Fab")
		)
		(fp_line
			(start -0.67945 -0.305054)
			(end -0.12065 -0.305054)
			(stroke
				(width 0.1)
				(type default)
			)
			(layer "F.Fab")
		)
		(fp_line
			(start -0.12065 -0.305054)
			(end -0.12065 -0.2794)
			(stroke
				(width 0.1)
				(type default)
			)
			(layer "F.Fab")
		)
		(pad "1" smd circle
			(at -0.40005 0 270)
			(size 0 0)
			(layers "F.Cu" "F.Mask" "F.Paste")
			(net "SW_PVCCIN_CPU1_BOOT6_R")
		)
		(pad "2" smd circle
			(at 0.40005 0 270)
			(size 0 0)
			(layers "F.Cu" "F.Mask" "F.Paste")
			(net "SW_PVCCIN_CPU1_BOOTR6")
		)
	)
	(footprint ""
		(layer "F.Cu")
		(at 375.255536 -105.483152 -90)
		(property "Reference" "R1366"
			(at 0 0 270)
			(layer "F.SilkS")
			(hide yes)
			(effects
				(font
					(size 1.27 1.27)
				)
			)
		)
		(property "Value" ""
			(at 0 0 270)
			(layer "F.Fab")
			(effects
				(font
					(size 1.27 1.27)
				)
			)
		)
		(duplicate_pad_numbers_are_jumpers no)
		(fp_line
			(start -0.7874 0.4064)
			(end -0.7874 -0.4064)
			(stroke
				(width 0.1524)
				(type default)
			)
			(layer "F.SilkS")
		)
		(fp_line
			(start 0.7874 0.4064)
			(end -0.7874 0.4064)
			(stroke
				(width 0.1524)
				(type default)
			)
			(layer "F.SilkS")
		)
		(fp_line
			(start -0.7874 -0.4064)
			(end 0.7874 -0.4064)
			(stroke
				(width 0.1524)
				(type default)
			)
			(layer "F.SilkS")
		)
		(fp_line
			(start 0.7874 -0.4064)
			(end 0.7874 0.4064)
			(stroke
				(width 0.1524)
				(type default)
			)
			(layer "F.SilkS")
		)
		(fp_line
			(start -0.67945 0.3048)
			(end -0.67945 -0.305054)
			(stroke
				(width 0.1)
				(type default)
			)
			(layer "F.Fab")
		)
		(fp_line
			(start -0.12065 0.3048)
			(end -0.67945 0.3048)
			(stroke
				(width 0.1)
				(type default)
			)
			(layer "F.Fab")
		)
		(fp_line
			(start 0.120396 0.3048)
			(end 0.120396 0.2794)
			(stroke
				(width 0.1)
				(type default)
			)
			(layer "F.Fab")
		)
		(fp_line
			(start 0.67945 0.3048)
			(end 0.120396 0.3048)
			(stroke
				(width 0.1)
				(type default)
			)
			(layer "F.Fab")
		)
		(fp_line
			(start -0.12065 0.2794)
			(end -0.12065 0.3048)
			(stroke
				(width 0.1)
				(type default)
			)
			(layer "F.Fab")
		)
		(fp_line
			(start 0.120396 0.2794)
			(end -0.12065 0.2794)
			(stroke
				(width 0.1)
				(type default)
			)
			(layer "F.Fab")
		)
		(fp_line
			(start -0.12065 -0.2794)
			(end 0.12065 -0.2794)
			(stroke
				(width 0.1)
				(type default)
			)
			(layer "F.Fab")
		)
		(fp_line
			(start 0.12065 -0.2794)
			(end 0.12065 -0.3048)
			(stroke
				(width 0.1)
				(type default)
			)
			(layer "F.Fab")
		)
		(fp_line
			(start 0.12065 -0.3048)
			(end 0.67945 -0.3048)
			(stroke
				(width 0.1)
				(type default)
			)
			(layer "F.Fab")
		)
		(fp_line
			(start 0.67945 -0.3048)
			(end 0.67945 0.3048)
			(stroke
				(width 0.1)
				(type default)
			)
			(layer "F.Fab")
		)
		(fp_line
			(start -0.67945 -0.305054)
			(end -0.12065 -0.305054)
			(stroke
				(width 0.1)
				(type default)
			)
			(layer "F.Fab")
		)
		(fp_line
			(start -0.12065 -0.305054)
			(end -0.12065 -0.2794)
			(stroke
				(width 0.1)
				(type default)
			)
			(layer "F.Fab")
		)
		(pad "1" smd circle
			(at -0.40005 0 270)
			(size 0 0)
			(layers "F.Cu" "F.Mask" "F.Paste")
			(net "JTAG_DBP_TDO")
		)
		(pad "2" smd circle
			(at 0.40005 0 270)
			(size 0 0)
			(layers "F.Cu" "F.Mask" "F.Paste")
			(net "JTAG_DBP_FB_TDO")
		)
	)
	(footprint ""
		(layer "F.Cu")
		(at 75.25893 -158.541974)
		(property "Reference" "R329"
			(at 0 0 0)
			(layer "F.SilkS")
			(hide yes)
			(effects
				(font
					(size 1.27 1.27)
				)
			)
		)
		(property "Value" ""
			(at 0 0 0)
			(layer "F.Fab")
			(effects
				(font
					(size 1.27 1.27)
				)
			)
		)
		(duplicate_pad_numbers_are_jumpers no)
		(fp_line
			(start -2.044192 -0.94361)
			(end -2.044192 0.898398)
			(stroke
				(width 0.1524)
				(type default)
			)
			(layer "F.SilkS")
		)
		(fp_line
			(start -2.044192 0.94361)
			(end 2.044192 0.94361)
			(stroke
				(width 0.1524)
				(type default)
			)
			(layer "F.SilkS")
		)
		(fp_line
			(start 2.044192 -0.94361)
			(end -2.044192 -0.94361)
			(stroke
				(width 0.1524)
				(type default)
			)
			(layer "F.SilkS")
		)
		(fp_line
			(start 2.044192 0.94361)
			(end 2.044192 -0.94361)
			(stroke
				(width 0.1524)
				(type default)
			)
			(layer "F.SilkS")
		)
		(fp_line
			(start -1.625092 -0.87503)
			(end -1.625092 0.87503)
			(stroke
				(width 0.1)
				(type default)
			)
			(layer "F.Fab")
		)
		(fp_line
			(start -1.625092 0.87503)
			(end 1.625092 0.87503)
			(stroke
				(width 0.1)
				(type default)
			)
			(layer "F.Fab")
		)
		(fp_line
			(start 1.625092 -0.87503)
			(end -1.625092 -0.87503)
			(stroke
				(width 0.1)
				(type default)
			)
			(layer "F.Fab")
		)
		(fp_line
			(start 1.625092 0.87503)
			(end 1.625092 -0.87503)
			(stroke
				(width 0.1)
				(type default)
			)
			(layer "F.Fab")
		)
		(pad "1" smd rect
			(at -1.450086 0)
			(size 0.9144 1.6002)
			(layers "F.Cu" "F.Mask" "F.Paste")
			(net "PVCCINFAON_CPU1")
		)
		(pad "2" smd rect
			(at 1.450086 0)
			(size 0.9144 1.6002)
			(layers "F.Cu" "F.Mask" "F.Paste")
			(net "PVNN_TERM_CPU1")
		)
	)
)
